# netlist discovery v1 revB.xlsx — Feuille1_3 (netlist-table)
| P  CODE 00 |  |  |  |
| P  UNITS CUST 0 |  |  |  |
| P  DIM   N |  |  |  |
| 367N/C | J2 |  | D1193UA00X+011851Y+021062X1575Y0000R090S0 |
| 367N/C | J2 |  | D1193UA00X+011851Y+014055X1575Y0000R090S0 |
| 317+12V | J2 | -1 | D0728PA00X+010197Y+015905X0984Y0000R090S0 |
| 317+12V | J2 | -2 | D0728PA00X+010197Y+017558X0984Y0000R090S0 |
| 317+12V | J2 | -3 | D0728PA00X+010197Y+019212X0984Y0000R090S0 |
| 317GND | J2 | -4 | D0728PA00X+011851Y+015905X0984Y0000R090S0 |
| 317GND | J2 | -5 | D0728PA00X+011851Y+017558X0984Y0000R090S0 |
| 317GND | J2 | -6 | D0728PA00X+011851Y+019212X0984Y0000R090S0 |
| 317GND | J4 | -6 | D0728PA00X+002323Y+015905X0984Y0000R270S0 |
| 317GND | J4 | -5 | D0728PA00X+002323Y+017558X0984Y0000R270S0 |
| 317GND | J4 | -4 | D0728PA00X+002323Y+019212X0984Y0000R270S0 |
| 317+12V | J4 | -3 | D0728PA00X+003977Y+015905X0984Y0000R270S0 |
| 317+12V | J4 | -2 | D0728PA00X+003977Y+017558X0984Y0000R270S0 |
| 317+12V | J4 | -1 | D0728PA00X+003977Y+019212X0984Y0000R270S0 |
| 367N/C | J4 |  | D1193UA00X+002323Y+021062X1575Y0000R270S0 |
| 367N/C | J4 |  | D1193UA00X+002323Y+014055X1575Y0000R270S0 |
| 367N/C | J5 |  | D1193UA00X+002323Y+002703X1575Y0000R270S0 |
| 367N/C | J5 |  | D1193UA00X+002323Y+009711X1575Y0000R270S0 |
| 317+12V | J5 | -1 | D0728PA00X+003977Y+007861X0984Y0000R270S0 |
| 317+12V | J5 | -2 | D0728PA00X+003977Y+006207X0984Y0000R270S0 |
| 317+12V | J5 | -3 | D0728PA00X+003977Y+004553X0984Y0000R270S0 |
| 317GND | J5 | -4 | D0728PA00X+002323Y+007861X0984Y0000R270S0 |
| 317GND | J5 | -5 | D0728PA00X+002323Y+006207X0984Y0000R270S0 |
| 317GND | J5 | -6 | D0728PA00X+002323Y+004553X0984Y0000R270S0 |
| 317GND | J6 | -6 | D0728PA00X+011851Y+007861X0984Y0000R090S0 |
| 317GND | J6 | -5 | D0728PA00X+011851Y+006207X0984Y0000R090S0 |
| 317GND | J6 | -4 | D0728PA00X+011851Y+004553X0984Y0000R090S0 |
| 317+12V | J6 | -3 | D0728PA00X+010197Y+007861X0984Y0000R090S0 |
| 317+12V | J6 | -2 | D0728PA00X+010197Y+006207X0984Y0000R090S0 |
| 317+12V | J6 | -1 | D0728PA00X+010197Y+004553X0984Y0000R090S0 |
| 367N/C | J6 |  | D1193UA00X+011851Y+002703X1575Y0000R090S0 |
| 367N/C | J6 |  | D1193UA00X+011851Y+009711X1575Y0000R090S0 |
| 317+12V | J1 | -8 | D0709PA00X+002402Y+026141X0984Y0000R270S0 |
| 317+12V | J1 | -7 | D0709PA00X+002402Y+027795X0984Y0000R270S0 |
| 317+12V | J1 | -6 | D0709PA00X+002402Y+029448X0984Y0000R270S0 |
| 317+12V | J1 | -5 | D0709PA00X+002402Y+031102X0984Y0000R270S0 |
| 317GND | J1 | -4 | D0709PA00X+004056Y+026141X0984Y0000R270S0 |
| 317GND | J1 | -3 | D0709PA00X+004056Y+027795X0984Y0000R270S0 |
| 317GND | J1 | -2 | D0709PA00X+004056Y+029448X0984Y0000R270S0 |
| 317GND | J1 | -1 | D0709PA00X+004056Y+031102X0984Y0000R270S0 |
| 367N/C | J1 |  | D1193UA00X+002323Y+032952X1575Y0000R270S0 |
| 367N/C | J1 |  | D1193UA00X+002323Y+024291X1575Y0000R270S0 |
| 367N/C | J3 |  | D1193UA00X+011851Y+032952X1575Y0000R090S0 |
| 367N/C | J3 |  | D1193UA00X+011851Y+024291X1575Y0000R090S0 |
| 317GND | J3 | -1 | D0709PA00X+010119Y+026141X0984Y0000R090S0 |
| 317GND | J3 | -2 | D0709PA00X+010119Y+027795X0984Y0000R090S0 |
| 317GND | J3 | -3 | D0709PA00X+010119Y+029448X0984Y0000R090S0 |
| 317GND | J3 | -4 | D0709PA00X+010119Y+031102X0984Y0000R090S0 |
| 317+12V | J3 | -5 | D0709PA00X+011772Y+026141X0984Y0000R090S0 |
| 317+12V | J3 | -6 | D0709PA00X+011772Y+027795X0984Y0000R090S0 |
| 317+12V | J3 | -7 | D0709PA00X+011772Y+029448X0984Y0000R090S0 |
| 317+12V | J3 | -8 | D0709PA00X+011772Y+031102X0984Y0000R090S0 |
| 317GND | W1 | -1 | D1575PA00X+055119Y-000001X1969Y0000R000S0 |
| 317GND | W2 | -1 | D1575PA00X+000001Y+035432X1969Y0000R000S0 |
| 317GND | W3 | -1 | D1575PA00X+055119Y+035432X1969Y0000R000S0 |
| 317GND | W4 | -1 | D1575PA00X+000001Y-000001X1969Y0000R000S0 |
| 317+12V | W5 | -1 | D2244PA00X+021654Y+030708X5906Y0000R000S0 |
| 317+12V | W6 | -1 | D2244PA00X+021654Y+021850X5906Y0000R000S0 |
| 317+12V | W7 | -1 | D2244PA00X+021654Y+012992X5906Y0000R000S0 |
| 317+12V | W8 | -1 | D2244PA00X+021654Y+004133X5906Y0000R000S0 |
| 317GND | W9 | -1 | D2244PA00X+045276Y+031791X5906Y0000R000S0 |
| 317GND | W10 | -1 | D2244PA00X+045276Y+022932X5906Y0000R000S0 |
| 317GND | W11 | -1 | D2244PA00X+045276Y+005216X5906Y0000R000S0 |
| 317GND | W12 | -1 | D2244PA00X+045276Y+014074X5906Y0000R000S0 |
| 999 |  |  |  |
